(kicad_pcb
	(version 20260206)
	(generator "pcbnew")
	(generator_version "10.0")
	(general
		(thickness 1.6)
		(legacy_teardrops no)
	)
	(paper "A4")
	(title_block
		(title "Bryce Canyon_R.DPB_16317-1_OCP.brd")
		(comment 1 "Bryce Canyon / footprints 2037-2044 of 2099")
	)
	(layers
		(0 "F.Cu" signal "TOP")
		(4 "In1.Cu" signal "L2GND")
		(6 "In2.Cu" signal "L3")
		(8 "In3.Cu" signal "L4VCC")
		(10 "In4.Cu" signal "L5VCC")
		(12 "In5.Cu" signal "L6")
		(14 "In6.Cu" signal "L7GND")
		(2 "B.Cu" signal "BOTTOM")
		(9 "F.Adhes" user "F.Adhesive")
		(11 "B.Adhes" user "B.Adhesive")
		(13 "F.Paste" user "Package Geometry/Pastemask Top")
		(15 "B.Paste" user "Package Geometry/Pastemask Bottom")
		(5 "F.SilkS" user "Ref Des/Silkscreen Top")
		(7 "B.SilkS" user "Ref Des/Silkscreen Bottom")
		(1 "F.Mask" user "Board Geometry/Soldermask Top")
		(3 "B.Mask" user "Board Geometry/Soldermask Bottom")
		(17 "Dwgs.User" user "User.Drawings")
		(19 "Cmts.User" user "User.Comments")
		(21 "Eco1.User" user "User.Eco1")
		(23 "Eco2.User" user "User.Eco2")
		(25 "Edge.Cuts" user "Board Geometry/Outline")
		(27 "Margin" user)
		(31 "F.CrtYd" user "Package Geometry/Place Bound Top")
		(29 "B.CrtYd" user "Package Geometry/Place Bound Bottom")
		(35 "F.Fab" user "Ref Des/Assembly Top")
		(33 "B.Fab" user "Ref Des/Assembly Bottom")
	)
	(footprint ""
		(layer "B.Cu")
		(at 255.905 -290.576 90)
		(property "Reference" "R1174"
			(at 0 0 90)
			(layer "B.SilkS")
			(hide yes)
			(effects
				(font
					(size 1.27 1.27)
				)
				(justify mirror)
			)
		)
		(property "Value" "0R6J-3-GP"
			(at 0.0508 -4.8514 90)
			(unlocked yes)
			(layer "B.Fab")
			(hide yes)
			(effects
				(font
					(size 1.016 1.016)
					(thickness 0.1524)
				)
				(justify mirror)
			)
		)
		(property "Device Type" "R1206H28"
			(at 0 -6.3754 90)
			(unlocked yes)
			(layer "B.Fab")
			(hide yes)
			(effects
				(font
					(size 1.016 1.016)
					(thickness 0.1524)
				)
				(justify mirror)
			)
		)
		(duplicate_pad_numbers_are_jumpers no)
		(fp_line
			(start 1.016 -2.2352)
			(end -1.016 -2.2352)
			(stroke
				(width 0.1524)
				(type default)
			)
			(layer "B.SilkS")
		)
		(fp_line
			(start -1.016 -2.2352)
			(end -1.016 2.2352)
			(stroke
				(width 0.1524)
				(type default)
			)
			(layer "B.SilkS")
		)
		(fp_line
			(start 1.016 2.2352)
			(end 1.016 -2.2352)
			(stroke
				(width 0.1524)
				(type default)
			)
			(layer "B.SilkS")
		)
		(fp_line
			(start -1.016 2.2352)
			(end 1.016 2.2352)
			(stroke
				(width 0.1524)
				(type default)
			)
			(layer "B.SilkS")
		)
		(fp_rect
			(start 1.0922 2.3114)
			(end -1.0922 -2.3114)
			(stroke
				(width 0)
				(type default)
			)
			(fill no)
			(layer "B.CrtYd")
		)
		(fp_poly
			(pts
				(xy 1.0922 -2.3114) (xy -1.0922 -2.3114) (xy -1.0922 2.3114) (xy 1.0922 2.3114)
			)
			(stroke
				(width 0)
				(type default)
			)
			(fill no)
			(layer "B.Fab")
		)
		(pad "1" smd rect
			(at 0 -1.397 270)
			(size 1.651 1.27)
			(layers "B.Cu" "B.Mask" "B.Paste")
			(net "P3V3_STBY_VIN")
		)
		(pad "2" smd rect
			(at 0 1.397 270)
			(size 1.651 1.27)
			(layers "B.Cu" "B.Mask" "B.Paste")
			(net "P12V_B")
		)
	)
	(footprint ""
		(layer "B.Cu")
		(at 21.123402 -229.54615)
		(property "Reference" "G2"
			(at 0 0 0)
			(layer "B.SilkS")
			(hide yes)
			(effects
				(font
					(size 1.27 1.27)
				)
				(justify mirror)
			)
		)
		(property "Value" "COPPER-CLOSE-GP-U"
			(at -0.0762 -2.8702 0)
			(unlocked yes)
			(layer "B.Fab")
			(hide yes)
			(effects
				(font
					(size 1.016 1.016)
					(thickness 0.1524)
				)
				(justify mirror)
			)
		)
		(property "Device Type" "CON2C-U"
			(at -0.0762 -4.3942 0)
			(unlocked yes)
			(layer "B.Fab")
			(hide yes)
			(effects
				(font
					(size 1.016 1.016)
					(thickness 0.1524)
				)
				(justify mirror)
			)
		)
		(duplicate_pad_numbers_are_jumpers no)
		(fp_rect
			(start 0.9398 0.9652)
			(end -0.9398 -0.9652)
			(stroke
				(width 0)
				(type default)
			)
			(fill no)
			(layer "B.CrtYd")
		)
		(fp_rect
			(start 0.9398 0.9652)
			(end -0.9398 -0.9652)
			(stroke
				(width 0)
				(type default)
			)
			(fill no)
			(layer "B.Fab")
		)
		(pad "1" smd custom
			(at 0 -0.5334 180)
			(size 0.17145 0.17145)
			(layers "B.Cu" "B.Mask" "B.Paste")
			(net "AGND_P5V_B_1")
			(options
				(clearance outline)
				(anchor circle)
			)
			(primitives
				(gr_poly
					(pts
						(xy -0.127 -0.3429) (xy -0.127 -0.1651) (xy -0.635 0.3429) (xy 0.635 0.3429) (xy 0.127 -0.1651)
						(xy 0.127 -0.3429)
					)
					(width 0)
					(fill yes)
				)
			)
		)
		(pad "2" smd custom
			(at 0 0.5334 180)
			(size 0.17145 0.17145)
			(layers "B.Cu" "B.Mask" "B.Paste")
			(net "GND")
			(options
				(clearance outline)
				(anchor circle)
			)
			(primitives
				(gr_poly
					(pts
						(xy -0.635 -0.3429) (xy -0.127 0.1651) (xy -0.127 0.3429) (xy 0.127 0.3429) (xy 0.127 0.1651)
						(xy 0.635 -0.3429)
					)
					(width 0)
					(fill yes)
				)
			)
		)
	)
	(footprint ""
		(layer "B.Cu")
		(at 244.856 -274.955 -90)
		(property "Reference" "R1182"
			(at 0 0 90)
			(layer "B.SilkS")
			(hide yes)
			(effects
				(font
					(size 1.27 1.27)
				)
				(justify mirror)
			)
		)
		(property "Value" "3D01R5F-GP"
			(at 0 -8.9535 270)
			(unlocked yes)
			(layer "B.Fab")
			(hide yes)
			(effects
				(font
					(size 1.27 1.016)
					(thickness 0.1524)
				)
				(justify mirror)
			)
		)
		(property "Device Type" "R805H24"
			(at 0 -10.6299 270)
			(unlocked yes)
			(layer "B.Fab")
			(hide yes)
			(effects
				(font
					(size 1.27 1.016)
					(thickness 0.1524)
				)
				(justify mirror)
			)
		)
		(duplicate_pad_numbers_are_jumpers no)
		(fp_line
			(start -0.889 1.7018)
			(end -0.889 -0.508)
			(stroke
				(width 0.1524)
				(type default)
			)
			(layer "B.SilkS")
		)
		(fp_line
			(start 0.889 1.7018)
			(end -0.889 1.7018)
			(stroke
				(width 0.1524)
				(type default)
			)
			(layer "B.SilkS")
		)
		(fp_line
			(start 0.889 0.0762)
			(end 0.889 1.7018)
			(stroke
				(width 0.1524)
				(type default)
			)
			(layer "B.SilkS")
		)
		(fp_line
			(start -0.889 -1.7018)
			(end -0.889 -0.381)
			(stroke
				(width 0.1524)
				(type default)
			)
			(layer "B.SilkS")
		)
		(fp_line
			(start -0.889 -1.7018)
			(end 0.889 -1.7018)
			(stroke
				(width 0.1524)
				(type default)
			)
			(layer "B.SilkS")
		)
		(fp_line
			(start 0.889 -1.7018)
			(end 0.889 0.2794)
			(stroke
				(width 0.1524)
				(type default)
			)
			(layer "B.SilkS")
		)
		(fp_poly
			(pts
				(xy -0.9652 -1.778) (xy -0.9652 1.778) (xy 0.9652 1.778) (xy 0.9652 -1.778)
			)
			(stroke
				(width 0)
				(type default)
			)
			(fill no)
			(layer "B.CrtYd")
		)
		(fp_rect
			(start 0.9652 1.778)
			(end -0.9652 -1.778)
			(stroke
				(width 0)
				(type default)
			)
			(fill no)
			(layer "B.Fab")
		)
		(pad "1" smd rect
			(at 0 -0.9652 90)
			(size 1.397 1.143)
			(layers "B.Cu" "B.Mask" "B.Paste")
			(net "P3V3_STBY_SNB")
		)
		(pad "2" smd rect
			(at 0 0.9652 90)
			(size 1.397 1.143)
			(layers "B.Cu" "B.Mask" "B.Paste")
			(net "GND")
		)
	)
	(footprint ""
		(layer "B.Cu")
		(at 247.4468 -286.5882 180)
		(property "Reference" "R1181"
			(at 0 0 0)
			(layer "B.SilkS")
			(hide yes)
			(effects
				(font
					(size 1.27 1.27)
				)
				(justify mirror)
			)
		)
		(property "Value" "2KR2F-3-GP"
			(at -0.064008 -3.993896 180)
			(unlocked yes)
			(layer "B.Fab")
			(hide yes)
			(effects
				(font
					(size 1.016 1.016)
					(thickness 0.1524)
				)
				(justify mirror)
			)
		)
		(property "Device Type" "R402H16"
			(at -0.064008 -5.517896 180)
			(unlocked yes)
			(layer "B.Fab")
			(hide yes)
			(effects
				(font
					(size 1.016 1.016)
					(thickness 0.1524)
				)
				(justify mirror)
			)
		)
		(duplicate_pad_numbers_are_jumpers no)
		(fp_line
			(start 0.508 -0.9398)
			(end 0.508 0.9398)
			(stroke
				(width 0.1524)
				(type default)
			)
			(layer "B.SilkS")
		)
		(fp_line
			(start -0.508 -0.9398)
			(end 0.508 -0.9398)
			(stroke
				(width 0.1524)
				(type default)
			)
			(layer "B.SilkS")
		)
		(fp_rect
			(start 0.508 0.9398)
			(end -0.508 -0.9398)
			(stroke
				(width 0)
				(type default)
			)
			(fill no)
			(layer "B.CrtYd")
		)
		(fp_rect
			(start 0.508 0.9398)
			(end -0.508 -0.9398)
			(stroke
				(width 0)
				(type default)
			)
			(fill no)
			(layer "B.Fab")
		)
		(pad "1" smd custom
			(at 0 -0.4445)
			(size 0.1397 0.1397)
			(layers "B.Cu" "B.Mask" "B.Paste")
			(net "P3V3_STBY_SW")
			(options
				(clearance outline)
				(anchor circle)
			)
			(primitives
				(gr_poly
					(pts
						(arc
							(start -0.1778 0.2794)
							(mid -0.249642 0.249642)
							(end -0.2794 0.1778)
						)
						(arc
							(start -0.2794 -0.1778)
							(mid -0.249642 -0.249642)
							(end -0.1778 -0.2794)
						)
						(arc
							(start 0.1778 -0.2794)
							(mid 0.249642 -0.249642)
							(end 0.2794 -0.1778)
						)
						(arc
							(start 0.2794 0.1778)
							(mid 0.249642 0.249642)
							(end 0.1778 0.2794)
						)
					)
					(width 0)
					(fill yes)
				)
			)
		)
		(pad "2" smd custom
			(at 0 0.4445)
			(size 0.1397 0.1397)
			(layers "B.Cu" "B.Mask" "B.Paste")
			(net "P3V3_STBY_VFB_R")
			(options
				(clearance outline)
				(anchor circle)
			)
			(primitives
				(gr_poly
					(pts
						(arc
							(start -0.1778 0.2794)
							(mid -0.249642 0.249642)
							(end -0.2794 0.1778)
						)
						(arc
							(start -0.2794 -0.1778)
							(mid -0.249642 -0.249642)
							(end -0.1778 -0.2794)
						)
						(arc
							(start 0.1778 -0.2794)
							(mid 0.249642 -0.249642)
							(end 0.2794 -0.1778)
						)
						(arc
							(start 0.2794 0.1778)
							(mid 0.249642 0.249642)
							(end 0.1778 0.2794)
						)
					)
					(width 0)
					(fill yes)
				)
			)
		)
	)
	(footprint ""
		(layer "B.Cu")
		(at 130.250946 -362.04017)
		(property "Reference" "Q212"
			(at 0 0 0)
			(layer "B.SilkS")
			(hide yes)
			(effects
				(font
					(size 1.27 1.27)
				)
				(justify mirror)
			)
		)
		(property "Value" "2N7002K-2-GP"
			(at -0.127 -8.9662 0)
			(unlocked yes)
			(layer "B.Fab")
			(hide yes)
			(effects
				(font
					(size 1.016 1.016)
					(thickness 0.1524)
				)
				(justify mirror)
			)
		)
		(property "Device Type" "SOT23DGS2D4H44"
			(at -0.127 -10.4902 0)
			(unlocked yes)
			(layer "B.Fab")
			(hide yes)
			(effects
				(font
					(size 1.016 1.016)
					(thickness 0.1524)
				)
				(justify mirror)
			)
		)
		(duplicate_pad_numbers_are_jumpers no)
		(fp_line
			(start -1.651 -1.778)
			(end 1.651 -1.778)
			(stroke
				(width 0.1524)
				(type default)
			)
			(layer "B.SilkS")
		)
		(fp_line
			(start -1.651 1.778)
			(end -1.651 -1.778)
			(stroke
				(width 0.1524)
				(type default)
			)
			(layer "B.SilkS")
		)
		(fp_line
			(start 1.651 -1.778)
			(end 1.651 1.778)
			(stroke
				(width 0.1524)
				(type default)
			)
			(layer "B.SilkS")
		)
		(fp_line
			(start 1.651 1.778)
			(end -1.651 1.778)
			(stroke
				(width 0.1524)
				(type default)
			)
			(layer "B.SilkS")
		)
		(fp_poly
			(pts
				(xy 1.778 1.8796) (xy 1.778 -1.8796) (xy -1.778 -1.8796) (xy -1.778 1.8796)
			)
			(stroke
				(width 0)
				(type default)
			)
			(fill no)
			(layer "B.CrtYd")
		)
		(fp_poly
			(pts
				(xy 1.778 1.8796) (xy 1.778 -1.8796) (xy -1.778 -1.8796) (xy -1.778 1.8796)
			)
			(stroke
				(width 0)
				(type default)
			)
			(fill no)
			(layer "B.Fab")
		)
		(pad "D" smd custom
			(at 0 -0.9525 180)
			(size 0.1905 0.1905)
			(layers "B.Cu" "B.Mask" "B.Paste")
			(net "GATE_FAN1")
			(options
				(clearance outline)
				(anchor circle)
			)
			(primitives
				(gr_poly
					(pts
						(arc
							(start -0.1778 -0.5715)
							(mid -0.321484 -0.511984)
							(end -0.381 -0.3683)
						)
						(arc
							(start -0.381 0.3683)
							(mid -0.321484 0.511984)
							(end -0.1778 0.5715)
						)
						(arc
							(start 0.1778 0.5715)
							(mid 0.321484 0.511984)
							(end 0.381 0.3683)
						)
						(arc
							(start 0.381 -0.3683)
							(mid 0.321484 -0.511984)
							(end 0.1778 -0.5715)
						)
					)
					(width 0)
					(fill yes)
				)
			)
		)
		(pad "G" smd custom
			(at 0.98425 0.9525 180)
			(size 0.1905 0.1905)
			(layers "B.Cu" "B.Mask" "B.Paste")
			(net "FAN_EN")
			(options
				(clearance outline)
				(anchor circle)
			)
			(primitives
				(gr_poly
					(pts
						(arc
							(start -0.1778 -0.5715)
							(mid -0.321484 -0.511984)
							(end -0.381 -0.3683)
						)
						(arc
							(start -0.381 0.3683)
							(mid -0.321484 0.511984)
							(end -0.1778 0.5715)
						)
						(arc
							(start 0.1778 0.5715)
							(mid 0.321484 0.511984)
							(end 0.381 0.3683)
						)
						(arc
							(start 0.381 -0.3683)
							(mid 0.321484 -0.511984)
							(end 0.1778 -0.5715)
						)
					)
					(width 0)
					(fill yes)
				)
			)
		)
		(pad "S" smd custom
			(at -0.98425 0.9525 180)
			(size 0.1905 0.1905)
			(layers "B.Cu" "B.Mask" "B.Paste")
			(net "GND")
			(options
				(clearance outline)
				(anchor circle)
			)
			(primitives
				(gr_poly
					(pts
						(arc
							(start -0.1778 -0.5715)
							(mid -0.321484 -0.511984)
							(end -0.381 -0.3683)
						)
						(arc
							(start -0.381 0.3683)
							(mid -0.321484 0.511984)
							(end -0.1778 0.5715)
						)
						(arc
							(start 0.1778 0.5715)
							(mid 0.321484 0.511984)
							(end 0.381 0.3683)
						)
						(arc
							(start 0.381 -0.3683)
							(mid 0.321484 -0.511984)
							(end 0.1778 -0.5715)
						)
					)
					(width 0)
					(fill yes)
				)
			)
		)
	)
	(footprint ""
		(layer "B.Cu")
		(at 71.52386 -117.167406 180)
		(property "Reference" "C652"
			(at 0 0 0)
			(layer "B.SilkS")
			(hide yes)
			(effects
				(font
					(size 1.27 1.27)
				)
				(justify mirror)
			)
		)
		(property "Value" "SC10U16V5KX-7-GP-U"
			(at 0.0762 -6.1214 180)
			(unlocked yes)
			(layer "B.Fab")
			(hide yes)
			(effects
				(font
					(size 1.016 1.016)
					(thickness 0.1524)
				)
				(justify mirror)
			)
		)
		(property "Device Type" "C805H58"
			(at 0.0762 -8.1534 180)
			(unlocked yes)
			(layer "B.Fab")
			(hide yes)
			(effects
				(font
					(size 1.016 1.016)
					(thickness 0.1524)
				)
				(justify mirror)
			)
		)
		(duplicate_pad_numbers_are_jumpers no)
		(fp_line
			(start -0.635 0)
			(end 0.635 0)
			(stroke
				(width 0.508)
				(type default)
			)
			(layer "B.SilkS")
		)
		(fp_rect
			(start 0.9652 1.778)
			(end -0.9652 -1.778)
			(stroke
				(width 0)
				(type default)
			)
			(fill no)
			(layer "B.CrtYd")
		)
		(fp_poly
			(pts
				(xy 0.9652 -1.778) (xy -0.9652 -1.778) (xy -0.9652 1.778) (xy 0.9652 1.778)
			)
			(stroke
				(width 0)
				(type default)
			)
			(fill no)
			(layer "B.Fab")
		)
		(pad "1" smd rect
			(at 0 -0.9652)
			(size 1.397 1.143)
			(layers "B.Cu" "B.Mask" "B.Paste")
			(net "P5V_B_2")
		)
		(pad "2" smd rect
			(at 0 0.9652)
			(size 1.397 1.143)
			(layers "B.Cu" "B.Mask" "B.Paste")
			(net "GND")
		)
	)
	(footprint ""
		(layer "B.Cu")
		(at 15.814802 -223.27235 180)
		(property "Reference" "C620"
			(at 0 0 0)
			(layer "B.SilkS")
			(hide yes)
			(effects
				(font
					(size 1.27 1.27)
				)
				(justify mirror)
			)
		)
		(property "Value" "SCD1U16V2KX-3GP"
			(at -1.1811 -2.7051 180)
			(unlocked yes)
			(layer "B.Fab")
			(hide yes)
			(effects
				(font
					(size 1.016 1.016)
					(thickness 0.1524)
				)
				(justify mirror)
			)
		)
		(property "Device Type" "C402H22"
			(at -1.1811 -4.2291 180)
			(unlocked yes)
			(layer "B.Fab")
			(hide yes)
			(effects
				(font
					(size 1.016 1.016)
					(thickness 0.1524)
				)
				(justify mirror)
			)
		)
		(duplicate_pad_numbers_are_jumpers no)
		(fp_rect
			(start 0.4318 0.9525)
			(end -0.4318 -0.9525)
			(stroke
				(width 0)
				(type default)
			)
			(fill no)
			(layer "B.CrtYd")
		)
		(fp_rect
			(start 0.4318 0.9525)
			(end -0.4318 -0.9525)
			(stroke
				(width 0)
				(type default)
			)
			(fill no)
			(layer "B.Fab")
		)
		(pad "1" smd custom
			(at 0 -0.4445)
			(size 0.1524 0.1524)
			(layers "B.Cu" "B.Mask" "B.Paste")
			(net "P12V_B_1_VIN_U31")
			(options
				(clearance outline)
				(anchor circle)
			)
			(primitives
				(gr_poly
					(pts
						(arc
							(start 0.3048 0.2032)
							(mid 0.275042 0.275042)
							(end 0.2032 0.3048)
						)
						(arc
							(start -0.2032 0.3048)
							(mid -0.275042 0.275042)
							(end -0.3048 0.2032)
						)
						(arc
							(start -0.3048 -0.2032)
							(mid -0.275042 -0.275042)
							(end -0.2032 -0.3048)
						)
						(arc
							(start 0.2032 -0.3048)
							(mid 0.275042 -0.275042)
							(end 0.3048 -0.2032)
						)
					)
					(width 0)
					(fill yes)
				)
			)
		)
		(pad "2" smd custom
			(at 0 0.4445)
			(size 0.1524 0.1524)
			(layers "B.Cu" "B.Mask" "B.Paste")
			(net "GND")
			(options
				(clearance outline)
				(anchor circle)
			)
			(primitives
				(gr_poly
					(pts
						(arc
							(start 0.3048 0.2032)
							(mid 0.275042 0.275042)
							(end 0.2032 0.3048)
						)
						(arc
							(start -0.2032 0.3048)
							(mid -0.275042 0.275042)
							(end -0.3048 0.2032)
						)
						(arc
							(start -0.3048 -0.2032)
							(mid -0.275042 -0.275042)
							(end -0.2032 -0.3048)
						)
						(arc
							(start 0.2032 -0.3048)
							(mid 0.275042 -0.275042)
							(end 0.3048 -0.2032)
						)
					)
					(width 0)
					(fill yes)
				)
			)
		)
	)
	(footprint ""
		(layer "B.Cu")
		(at 22.591014 -229.543864 180)
		(property "Reference" "R1113"
			(at 0 0 0)
			(layer "B.SilkS")
			(hide yes)
			(effects
				(font
					(size 1.27 1.27)
				)
				(justify mirror)
			)
		)
		(property "Value" "10KR2F-2-GP"
			(at -0.064008 -3.993896 180)
			(unlocked yes)
			(layer "B.Fab")
			(hide yes)
			(effects
				(font
					(size 1.016 1.016)
					(thickness 0.1524)
				)
				(justify mirror)
			)
		)
		(property "Device Type" "R402H16"
			(at -0.064008 -5.517896 180)
			(unlocked yes)
			(layer "B.Fab")
			(hide yes)
			(effects
				(font
					(size 1.016 1.016)
					(thickness 0.1524)
				)
				(justify mirror)
			)
		)
		(duplicate_pad_numbers_are_jumpers no)
		(fp_line
			(start 0.508 -0.9398)
			(end 0.508 0.9398)
			(stroke
				(width 0.1524)
				(type default)
			)
			(layer "B.SilkS")
		)
		(fp_line
			(start -0.508 -0.9398)
			(end 0.508 -0.9398)
			(stroke
				(width 0.1524)
				(type default)
			)
			(layer "B.SilkS")
		)
		(fp_rect
			(start 0.508 0.9398)
			(end -0.508 -0.9398)
			(stroke
				(width 0)
				(type default)
			)
			(fill no)
			(layer "B.CrtYd")
		)
		(fp_rect
			(start 0.508 0.9398)
			(end -0.508 -0.9398)
			(stroke
				(width 0)
				(type default)
			)
			(fill no)
			(layer "B.Fab")
		)
		(pad "1" smd custom
			(at 0 -0.4445)
			(size 0.1397 0.1397)
			(layers "B.Cu" "B.Mask" "B.Paste")
			(net "P5V_B_1_VFB")
			(options
				(clearance outline)
				(anchor circle)
			)
			(primitives
				(gr_poly
					(pts
						(arc
							(start -0.1778 0.2794)
							(mid -0.249642 0.249642)
							(end -0.2794 0.1778)
						)
						(arc
							(start -0.2794 -0.1778)
							(mid -0.249642 -0.249642)
							(end -0.1778 -0.2794)
						)
						(arc
							(start 0.1778 -0.2794)
							(mid 0.249642 -0.249642)
							(end 0.2794 -0.1778)
						)
						(arc
							(start 0.2794 0.1778)
							(mid 0.249642 0.249642)
							(end 0.1778 0.2794)
						)
					)
					(width 0)
					(fill yes)
				)
			)
		)
		(pad "2" smd custom
			(at 0 0.4445)
			(size 0.1397 0.1397)
			(layers "B.Cu" "B.Mask" "B.Paste")
			(net "AGND_P5V_B_1")
			(options
				(clearance outline)
				(anchor circle)
			)
			(primitives
				(gr_poly
					(pts
						(arc
							(start -0.1778 0.2794)
							(mid -0.249642 0.249642)
							(end -0.2794 0.1778)
						)
						(arc
							(start -0.2794 -0.1778)
							(mid -0.249642 -0.249642)
							(end -0.1778 -0.2794)
						)
						(arc
							(start 0.1778 -0.2794)
							(mid 0.249642 -0.249642)
							(end 0.2794 -0.1778)
						)
						(arc
							(start 0.2794 0.1778)
							(mid 0.249642 0.249642)
							(end 0.1778 0.2794)
						)
					)
					(width 0)
					(fill yes)
				)
			)
		)
	)
)
